# T6G (Grand Teton) — schematic netlist excerpt (pin names and nets, part order shuffled) for the footprints in the layout excerpt that follows; sources: Cadence DE-HDL packaged netlist, KiCad conversion of 04192023_DAF0TMB3IC0_F0TG_MB_C_brd_V02_OCP.brd

R6017  Q_RES  2K 5% EMPTY  pkg 0402LF  page 151 : A = P3V3_AUX ; B = SGPIO_SCM_CLK_<0>
R175  Q_RES  0 5% CHIP  pkg 0402LF  page 210 : A = SMB_VR_3V3STBY_SCL ; B = PVDDCR_CPU0_P1_PMSCL_R

(kicad_pcb
	(version 20260206)
	(generator "pcbnew")
	(generator_version "10.0")
	(general
		(thickness 1.6)
		(legacy_teardrops no)
	)
	(paper "A4")
	(title_block
		(title "04192023_DAF0TMB3IC0_F0TG_MB_C_brd_V02_OCP.brd")
		(comment 1 "Grand Teton / footprints 7365-7366 of 8354")
	)
	(layers
		(0 "F.Cu" signal "TOP")
		(4 "In1.Cu" signal "GND")
		(6 "In2.Cu" signal "IN1")
		(8 "In3.Cu" signal "GND1")
		(10 "In4.Cu" signal "IN2")
		(12 "In5.Cu" signal "GND2")
		(14 "In6.Cu" signal "IN3")
		(16 "In7.Cu" signal "GND3")
		(18 "In8.Cu" signal "VCC")
		(20 "In9.Cu" signal "VCC1")
		(22 "In10.Cu" signal "GND4")
		(24 "In11.Cu" signal "IN4")
		(26 "In12.Cu" signal "GND5")
		(28 "In13.Cu" signal "IN5")
		(30 "In14.Cu" signal "GND6")
		(32 "In15.Cu" signal "IN6")
		(34 "In16.Cu" signal "GND7")
		(2 "B.Cu" signal "BOTTOM")
		(9 "F.Adhes" user "F.Adhesive")
		(11 "B.Adhes" user "B.Adhesive")
		(13 "F.Paste" user "Package Geometry/Pastemask Top")
		(15 "B.Paste" user "Package Geometry/Pastemask Bottom")
		(5 "F.SilkS" user "Ref Des/Silkscreen Top")
		(7 "B.SilkS" user "Ref Des/Silkscreen Bottom")
		(1 "F.Mask" user "Board Geometry/Soldermask Top")
		(3 "B.Mask" user "Board Geometry/Soldermask Bottom")
		(17 "Dwgs.User" user "User.Drawings")
		(19 "Cmts.User" user "User.Comments")
		(21 "Eco1.User" user "User.Eco1")
		(23 "Eco2.User" user "User.Eco2")
		(25 "Edge.Cuts" user "Board Geometry/Outline")
		(27 "Margin" user)
		(31 "F.CrtYd" user "Package Geometry/Place Bound Top")
		(29 "B.CrtYd" user "Package Geometry/Place Bound Bottom")
		(35 "F.Fab" user "Ref Des/Assembly Top")
		(33 "B.Fab" user "Ref Des/Assembly Bottom")
	)
	(footprint ""
		(layer "B.Cu")
		(at 173.609 -98.135948 90)
		(property "Reference" "R6017"
			(at 0 0 90)
			(layer "B.SilkS")
			(hide yes)
			(effects
				(font
					(size 1.27 1.27)
				)
				(justify mirror)
			)
		)
		(property "Value" ""
			(at 0 0 90)
			(layer "B.Fab")
			(effects
				(font
					(size 1.27 1.27)
				)
				(justify mirror)
			)
		)
		(duplicate_pad_numbers_are_jumpers no)
		(fp_line
			(start 0.7874 -0.4064)
			(end -0.7874 -0.4064)
			(stroke
				(width 0.1524)
				(type default)
			)
			(layer "B.SilkS")
		)
		(fp_line
			(start -0.7874 -0.4064)
			(end -0.7874 0.4064)
			(stroke
				(width 0.1524)
				(type default)
			)
			(layer "B.SilkS")
		)
		(fp_line
			(start 0.7874 0.4064)
			(end 0.7874 -0.4064)
			(stroke
				(width 0.1524)
				(type default)
			)
			(layer "B.SilkS")
		)
		(fp_line
			(start -0.7874 0.4064)
			(end 0.7874 0.4064)
			(stroke
				(width 0.1524)
				(type default)
			)
			(layer "B.SilkS")
		)
		(fp_line
			(start 0.67945 -0.305054)
			(end 0.12065 -0.305054)
			(stroke
				(width 0.1)
				(type default)
			)
			(layer "B.Fab")
		)
		(fp_line
			(start 0.12065 -0.305054)
			(end 0.12065 -0.2794)
			(stroke
				(width 0.1)
				(type default)
			)
			(layer "B.Fab")
		)
		(fp_line
			(start -0.12065 -0.3048)
			(end -0.67945 -0.3048)
			(stroke
				(width 0.1)
				(type default)
			)
			(layer "B.Fab")
		)
		(fp_line
			(start -0.67945 -0.3048)
			(end -0.67945 0.3048)
			(stroke
				(width 0.1)
				(type default)
			)
			(layer "B.Fab")
		)
		(fp_line
			(start 0.12065 -0.2794)
			(end -0.12065 -0.2794)
			(stroke
				(width 0.1)
				(type default)
			)
			(layer "B.Fab")
		)
		(fp_line
			(start -0.12065 -0.2794)
			(end -0.12065 -0.3048)
			(stroke
				(width 0.1)
				(type default)
			)
			(layer "B.Fab")
		)
		(fp_line
			(start 0.12065 0.2794)
			(end 0.12065 0.3048)
			(stroke
				(width 0.1)
				(type default)
			)
			(layer "B.Fab")
		)
		(fp_line
			(start -0.120396 0.2794)
			(end 0.12065 0.2794)
			(stroke
				(width 0.1)
				(type default)
			)
			(layer "B.Fab")
		)
		(fp_line
			(start 0.67945 0.3048)
			(end 0.67945 -0.305054)
			(stroke
				(width 0.1)
				(type default)
			)
			(layer "B.Fab")
		)
		(fp_line
			(start 0.12065 0.3048)
			(end 0.67945 0.3048)
			(stroke
				(width 0.1)
				(type default)
			)
			(layer "B.Fab")
		)
		(fp_line
			(start -0.120396 0.3048)
			(end -0.120396 0.2794)
			(stroke
				(width 0.1)
				(type default)
			)
			(layer "B.Fab")
		)
		(fp_line
			(start -0.67945 0.3048)
			(end -0.120396 0.3048)
			(stroke
				(width 0.1)
				(type default)
			)
			(layer "B.Fab")
		)
		(pad "1" smd circle
			(at 0.40005 0 270)
			(size 0 0)
			(layers "B.Cu" "B.Mask" "B.Paste")
			(net "P3V3_AUX")
		)
		(pad "2" smd circle
			(at -0.40005 0 270)
			(size 0 0)
			(layers "B.Cu" "B.Mask" "B.Paste")
			(net "SGPIO_SCM_CLK_<0>")
		)
	)
	(footprint ""
		(layer "B.Cu")
		(at 91.987878 -138.40841 -90)
		(property "Reference" "R175"
			(at 0 0 90)
			(layer "B.SilkS")
			(hide yes)
			(effects
				(font
					(size 1.27 1.27)
				)
				(justify mirror)
			)
		)
		(property "Value" ""
			(at 0 0 90)
			(layer "B.Fab")
			(effects
				(font
					(size 1.27 1.27)
				)
				(justify mirror)
			)
		)
		(duplicate_pad_numbers_are_jumpers no)
		(fp_line
			(start -0.7874 0.4064)
			(end 0.7874 0.4064)
			(stroke
				(width 0.1524)
				(type default)
			)
			(layer "B.SilkS")
		)
		(fp_line
			(start 0.7874 0.4064)
			(end 0.7874 -0.4064)
			(stroke
				(width 0.1524)
				(type default)
			)
			(layer "B.SilkS")
		)
		(fp_line
			(start -0.7874 -0.4064)
			(end -0.7874 0.4064)
			(stroke
				(width 0.1524)
				(type default)
			)
			(layer "B.SilkS")
		)
		(fp_line
			(start 0.7874 -0.4064)
			(end -0.7874 -0.4064)
			(stroke
				(width 0.1524)
				(type default)
			)
			(layer "B.SilkS")
		)
		(fp_line
			(start -0.67945 0.3048)
			(end -0.120396 0.3048)
			(stroke
				(width 0.1)
				(type default)
			)
			(layer "B.Fab")
		)
		(fp_line
			(start -0.120396 0.3048)
			(end -0.120396 0.2794)
			(stroke
				(width 0.1)
				(type default)
			)
			(layer "B.Fab")
		)
		(fp_line
			(start 0.12065 0.3048)
			(end 0.67945 0.3048)
			(stroke
				(width 0.1)
				(type default)
			)
			(layer "B.Fab")
		)
		(fp_line
			(start 0.67945 0.3048)
			(end 0.67945 -0.305054)
			(stroke
				(width 0.1)
				(type default)
			)
			(layer "B.Fab")
		)
		(fp_line
			(start -0.120396 0.2794)
			(end 0.12065 0.2794)
			(stroke
				(width 0.1)
				(type default)
			)
			(layer "B.Fab")
		)
		(fp_line
			(start 0.12065 0.2794)
			(end 0.12065 0.3048)
			(stroke
				(width 0.1)
				(type default)
			)
			(layer "B.Fab")
		)
		(fp_line
			(start -0.12065 -0.2794)
			(end -0.12065 -0.3048)
			(stroke
				(width 0.1)
				(type default)
			)
			(layer "B.Fab")
		)
		(fp_line
			(start 0.12065 -0.2794)
			(end -0.12065 -0.2794)
			(stroke
				(width 0.1)
				(type default)
			)
			(layer "B.Fab")
		)
		(fp_line
			(start -0.67945 -0.3048)
			(end -0.67945 0.3048)
			(stroke
				(width 0.1)
				(type default)
			)
			(layer "B.Fab")
		)
		(fp_line
			(start -0.12065 -0.3048)
			(end -0.67945 -0.3048)
			(stroke
				(width 0.1)
				(type default)
			)
			(layer "B.Fab")
		)
		(fp_line
			(start 0.12065 -0.305054)
			(end 0.12065 -0.2794)
			(stroke
				(width 0.1)
				(type default)
			)
			(layer "B.Fab")
		)
		(fp_line
			(start 0.67945 -0.305054)
			(end 0.12065 -0.305054)
			(stroke
				(width 0.1)
				(type default)
			)
			(layer "B.Fab")
		)
		(pad "1" smd circle
			(at 0.40005 0 90)
			(size 0 0)
			(layers "B.Cu" "B.Mask" "B.Paste")
			(net "SMB_VR_3V3STBY_SCL")
		)
		(pad "2" smd circle
			(at -0.40005 0 90)
			(size 0 0)
			(layers "B.Cu" "B.Mask" "B.Paste")
			(net "PVDDCR_CPU0_P1_PMSCL_R")
		)
	)
)
